(kicad_pcb
	(version 20260206)
	(generator "pcbnew")
	(generator_version "10.0")
	(general
		(thickness 1.6)
		(legacy_teardrops no)
	)
	(paper "A4")
	(title_block
		(title "03242023_DA0F0TMBIJ0_F0T_Motherboard_J_brd_V01_OCP.brd")
		(comment 1 "Grand Teton / footprints 1800-1806 of 6105")
	)
	(layers
		(0 "F.Cu" signal "TOP")
		(4 "In1.Cu" signal "GND")
		(6 "In2.Cu" signal "IN1")
		(8 "In3.Cu" signal "GND1")
		(10 "In4.Cu" signal "IN2")
		(12 "In5.Cu" signal "GND2")
		(14 "In6.Cu" signal "IN3")
		(16 "In7.Cu" signal "GND3")
		(18 "In8.Cu" signal "VCC")
		(20 "In9.Cu" signal "VCC1")
		(22 "In10.Cu" signal "GND4")
		(24 "In11.Cu" signal "IN4")
		(26 "In12.Cu" signal "GND5")
		(28 "In13.Cu" signal "IN5")
		(30 "In14.Cu" signal "GND6")
		(32 "In15.Cu" signal "IN6")
		(34 "In16.Cu" signal "GND7")
		(2 "B.Cu" signal "BOTTOM")
		(9 "F.Adhes" user "F.Adhesive")
		(11 "B.Adhes" user "B.Adhesive")
		(13 "F.Paste" user "Package Geometry/Pastemask Top")
		(15 "B.Paste" user "Package Geometry/Pastemask Bottom")
		(5 "F.SilkS" user "Ref Des/Silkscreen Top")
		(7 "B.SilkS" user "Ref Des/Silkscreen Bottom")
		(1 "F.Mask" user "Board Geometry/Soldermask Top")
		(3 "B.Mask" user "Board Geometry/Soldermask Bottom")
		(17 "Dwgs.User" user "User.Drawings")
		(19 "Cmts.User" user "User.Comments")
		(21 "Eco1.User" user "User.Eco1")
		(23 "Eco2.User" user "User.Eco2")
		(25 "Edge.Cuts" user "Board Geometry/Outline")
		(27 "Margin" user)
		(31 "F.CrtYd" user "Package Geometry/Place Bound Top")
		(29 "B.CrtYd" user "Package Geometry/Place Bound Bottom")
		(35 "F.Fab" user "Ref Des/Assembly Top")
		(33 "B.Fab" user "Ref Des/Assembly Bottom")
	)
	(footprint ""
		(layer "F.Cu")
		(at 268.28115 -41.435274)
		(property "Reference" "JP9"
			(at -1.4097 -2.009648 0)
			(unlocked yes)
			(layer "F.SilkS")
			(effects
				(font
					(size 0.7874 0.5842)
					(thickness 0.1524)
				)
				(justify left)
			)
		)
		(property "Value" ""
			(at 0 0 0)
			(layer "F.Fab")
			(effects
				(font
					(size 1.27 1.27)
				)
			)
		)
		(duplicate_pad_numbers_are_jumpers no)
		(fp_line
			(start -1.249934 -1.320038)
			(end 1.249934 -1.320038)
			(stroke
				(width 0.1524)
				(type default)
			)
			(layer "F.SilkS")
		)
		(fp_line
			(start -1.249934 6.400038)
			(end -1.249934 -1.320038)
			(stroke
				(width 0.1524)
				(type default)
			)
			(layer "F.SilkS")
		)
		(fp_line
			(start 1.249934 -1.320038)
			(end 1.249934 6.400038)
			(stroke
				(width 0.1524)
				(type default)
			)
			(layer "F.SilkS")
		)
		(fp_line
			(start 1.249934 6.400038)
			(end -1.249934 6.400038)
			(stroke
				(width 0.1524)
				(type default)
			)
			(layer "F.SilkS")
		)
		(fp_poly
			(pts
				(xy -1.406652 0) (xy -2.13741 0.365506) (xy -2.13741 -0.365506)
			)
			(stroke
				(width 0)
				(type default)
			)
			(fill yes)
			(layer "F.SilkS")
		)
		(fp_line
			(start -1.249934 -1.320038)
			(end 1.249934 -1.320038)
			(stroke
				(width 0.1)
				(type default)
			)
			(layer "F.Fab")
		)
		(fp_line
			(start -1.249934 6.400038)
			(end -1.249934 -1.320038)
			(stroke
				(width 0.1)
				(type default)
			)
			(layer "F.Fab")
		)
		(fp_line
			(start 1.249934 -1.320038)
			(end 1.249934 6.400038)
			(stroke
				(width 0.1)
				(type default)
			)
			(layer "F.Fab")
		)
		(fp_line
			(start 1.249934 6.400038)
			(end -1.249934 6.400038)
			(stroke
				(width 0.1)
				(type default)
			)
			(layer "F.Fab")
		)
		(fp_poly
			(pts
				(xy -2.5654 -0.556514) (xy -1.452372 0) (xy -2.5654 0.556514)
			)
			(stroke
				(width 0)
				(type default)
			)
			(fill yes)
			(layer "F.Fab")
		)
		(fp_text user "3"
			(at -1.778 5.13207 0)
			(unlocked yes)
			(layer "F.SilkS")
			(effects
				(font
					(size 0.7874 0.5842)
					(thickness 0.1524)
				)
			)
		)
		(fp_text user "3"
			(at -1.1557 5.18287 0)
			(unlocked yes)
			(layer "B.SilkS")
			(effects
				(font
					(size 0.7874 0.5842)
					(thickness 0.1524)
				)
				(justify mirror)
			)
		)
		(fp_text user "1"
			(at -1.143 0.02667 0)
			(unlocked yes)
			(layer "B.SilkS")
			(effects
				(font
					(size 0.7874 0.5842)
					(thickness 0.1524)
				)
				(justify mirror)
			)
		)
		(fp_text user "3"
			(at -1.1557 5.18287 0)
			(unlocked yes)
			(layer "B.Fab")
			(effects
				(font
					(size 0.7874 0.5842)
					(thickness 0.1524)
				)
				(justify mirror)
			)
		)
		(fp_text user "1"
			(at -1.143 0.02667 0)
			(unlocked yes)
			(layer "B.Fab")
			(effects
				(font
					(size 0.7874 0.5842)
					(thickness 0.1524)
				)
				(justify mirror)
			)
		)
		(fp_text user "3"
			(at -1.778 5.13207 0)
			(unlocked yes)
			(layer "F.Fab")
			(effects
				(font
					(size 0.7874 0.5842)
					(thickness 0.1524)
				)
			)
		)
		(pad "1" thru_hole rect
			(at 0 0)
			(size 1.5494 1.5494)
			(drill 1.0414)
			(layers "*.Cu" "*.Mask")
			(remove_unused_layers no)
			(net "SMB_SML1_PMBUS_3V3AUX_PCH_SCL_1")
			(clearance 0)
			(padstack
				(mode front_inner_back)
				(layer "Inner"
					(shape circle)
					(size 1.5494 1.5494)
					(clearance 0)
				)
				(layer "B.Cu"
					(shape rect)
					(size 1.5494 1.5494)
					(clearance 0)
				)
			)
		)
		(pad "2" thru_hole circle
			(at 0 2.54)
			(size 1.5494 1.5494)
			(drill 1.0414)
			(layers "*.Cu" "*.Mask")
			(remove_unused_layers no)
			(net "GND")
			(clearance 0)
		)
		(pad "3" thru_hole circle
			(at 0 5.08)
			(size 1.5494 1.5494)
			(drill 1.0414)
			(layers "*.Cu" "*.Mask")
			(remove_unused_layers no)
			(net "SMB_SML1_PMBUS_3V3AUX_PCH_SDA_1")
			(clearance 0)
		)
	)
	(footprint ""
		(layer "F.Cu")
		(at 300.6852 -28.3464 180)
		(property "Reference" "R1203"
			(at 0 0 180)
			(layer "F.SilkS")
			(hide yes)
			(effects
				(font
					(size 1.27 1.27)
				)
			)
		)
		(property "Value" ""
			(at 0 0 180)
			(layer "F.Fab")
			(effects
				(font
					(size 1.27 1.27)
				)
			)
		)
		(duplicate_pad_numbers_are_jumpers no)
		(fp_line
			(start 0.7874 0.4064)
			(end -0.7874 0.4064)
			(stroke
				(width 0.1524)
				(type default)
			)
			(layer "F.SilkS")
		)
		(fp_line
			(start 0.7874 -0.4064)
			(end 0.7874 0.4064)
			(stroke
				(width 0.1524)
				(type default)
			)
			(layer "F.SilkS")
		)
		(fp_line
			(start -0.7874 0.4064)
			(end -0.7874 -0.4064)
			(stroke
				(width 0.1524)
				(type default)
			)
			(layer "F.SilkS")
		)
		(fp_line
			(start -0.7874 -0.4064)
			(end 0.7874 -0.4064)
			(stroke
				(width 0.1524)
				(type default)
			)
			(layer "F.SilkS")
		)
		(fp_line
			(start 0.67945 0.3048)
			(end 0.120396 0.3048)
			(stroke
				(width 0.1)
				(type default)
			)
			(layer "F.Fab")
		)
		(fp_line
			(start 0.67945 -0.3048)
			(end 0.67945 0.3048)
			(stroke
				(width 0.1)
				(type default)
			)
			(layer "F.Fab")
		)
		(fp_line
			(start 0.12065 -0.2794)
			(end 0.12065 -0.3048)
			(stroke
				(width 0.1)
				(type default)
			)
			(layer "F.Fab")
		)
		(fp_line
			(start 0.12065 -0.3048)
			(end 0.67945 -0.3048)
			(stroke
				(width 0.1)
				(type default)
			)
			(layer "F.Fab")
		)
		(fp_line
			(start 0.120396 0.3048)
			(end 0.120396 0.2794)
			(stroke
				(width 0.1)
				(type default)
			)
			(layer "F.Fab")
		)
		(fp_line
			(start 0.120396 0.2794)
			(end -0.12065 0.2794)
			(stroke
				(width 0.1)
				(type default)
			)
			(layer "F.Fab")
		)
		(fp_line
			(start -0.12065 0.3048)
			(end -0.67945 0.3048)
			(stroke
				(width 0.1)
				(type default)
			)
			(layer "F.Fab")
		)
		(fp_line
			(start -0.12065 0.2794)
			(end -0.12065 0.3048)
			(stroke
				(width 0.1)
				(type default)
			)
			(layer "F.Fab")
		)
		(fp_line
			(start -0.12065 -0.2794)
			(end 0.12065 -0.2794)
			(stroke
				(width 0.1)
				(type default)
			)
			(layer "F.Fab")
		)
		(fp_line
			(start -0.12065 -0.305054)
			(end -0.12065 -0.2794)
			(stroke
				(width 0.1)
				(type default)
			)
			(layer "F.Fab")
		)
		(fp_line
			(start -0.67945 0.3048)
			(end -0.67945 -0.305054)
			(stroke
				(width 0.1)
				(type default)
			)
			(layer "F.Fab")
		)
		(fp_line
			(start -0.67945 -0.305054)
			(end -0.12065 -0.305054)
			(stroke
				(width 0.1)
				(type default)
			)
			(layer "F.Fab")
		)
		(pad "1" smd circle
			(at -0.40005 0 180)
			(size 0 0)
			(layers "F.Cu" "F.Mask" "F.Paste")
			(net "P3V_BAT")
		)
		(pad "2" smd circle
			(at 0.40005 0 180)
			(size 0 0)
			(layers "F.Cu" "F.Mask" "F.Paste")
			(net "P3V_BAT_R")
		)
	)
	(footprint ""
		(layer "F.Cu")
		(at 223.378522 -74.510138 180)
		(property "Reference" "PC2213"
			(at 0 0 180)
			(layer "F.SilkS")
			(hide yes)
			(effects
				(font
					(size 1.27 1.27)
				)
			)
		)
		(property "Value" ""
			(at 0 0 180)
			(layer "F.Fab")
			(effects
				(font
					(size 1.27 1.27)
				)
			)
		)
		(duplicate_pad_numbers_are_jumpers no)
		(fp_line
			(start 0.7874 0.4064)
			(end -0.7874 0.4064)
			(stroke
				(width 0.1524)
				(type default)
			)
			(layer "F.SilkS")
		)
		(fp_line
			(start 0.7874 -0.4064)
			(end 0.7874 0.4064)
			(stroke
				(width 0.1524)
				(type default)
			)
			(layer "F.SilkS")
		)
		(fp_line
			(start -0.7874 0.4064)
			(end -0.7874 -0.4064)
			(stroke
				(width 0.1524)
				(type default)
			)
			(layer "F.SilkS")
		)
		(fp_line
			(start -0.7874 -0.4064)
			(end 0.7874 -0.4064)
			(stroke
				(width 0.1524)
				(type default)
			)
			(layer "F.SilkS")
		)
		(fp_line
			(start 0.67945 0.3048)
			(end 0.120396 0.3048)
			(stroke
				(width 0.1)
				(type default)
			)
			(layer "F.Fab")
		)
		(fp_line
			(start 0.67945 -0.3048)
			(end 0.67945 0.3048)
			(stroke
				(width 0.1)
				(type default)
			)
			(layer "F.Fab")
		)
		(fp_line
			(start 0.12065 -0.2794)
			(end 0.12065 -0.3048)
			(stroke
				(width 0.1)
				(type default)
			)
			(layer "F.Fab")
		)
		(fp_line
			(start 0.12065 -0.3048)
			(end 0.67945 -0.3048)
			(stroke
				(width 0.1)
				(type default)
			)
			(layer "F.Fab")
		)
		(fp_line
			(start 0.120396 0.3048)
			(end 0.120396 0.2794)
			(stroke
				(width 0.1)
				(type default)
			)
			(layer "F.Fab")
		)
		(fp_line
			(start 0.120396 0.2794)
			(end -0.12065 0.2794)
			(stroke
				(width 0.1)
				(type default)
			)
			(layer "F.Fab")
		)
		(fp_line
			(start -0.12065 0.3048)
			(end -0.67945 0.3048)
			(stroke
				(width 0.1)
				(type default)
			)
			(layer "F.Fab")
		)
		(fp_line
			(start -0.12065 0.2794)
			(end -0.12065 0.3048)
			(stroke
				(width 0.1)
				(type default)
			)
			(layer "F.Fab")
		)
		(fp_line
			(start -0.12065 -0.2794)
			(end 0.12065 -0.2794)
			(stroke
				(width 0.1)
				(type default)
			)
			(layer "F.Fab")
		)
		(fp_line
			(start -0.12065 -0.305054)
			(end -0.12065 -0.2794)
			(stroke
				(width 0.1)
				(type default)
			)
			(layer "F.Fab")
		)
		(fp_line
			(start -0.67945 0.3048)
			(end -0.67945 -0.305054)
			(stroke
				(width 0.1)
				(type default)
			)
			(layer "F.Fab")
		)
		(fp_line
			(start -0.67945 -0.305054)
			(end -0.12065 -0.305054)
			(stroke
				(width 0.1)
				(type default)
			)
			(layer "F.Fab")
		)
		(pad "1" smd circle
			(at -0.40005 0 180)
			(size 0 0)
			(layers "F.Cu" "F.Mask" "F.Paste")
			(net "P3V3_E1S_0_R")
		)
		(pad "2" smd circle
			(at 0.40005 0 180)
			(size 0 0)
			(layers "F.Cu" "F.Mask" "F.Paste")
			(net "P3V3_E1S_GATE_0")
		)
	)
	(footprint ""
		(layer "F.Cu")
		(at 175.06188 -21.173948 180)
		(property "Reference" "PC2242"
			(at 0 0 180)
			(layer "F.SilkS")
			(hide yes)
			(effects
				(font
					(size 1.27 1.27)
				)
			)
		)
		(property "Value" ""
			(at 0 0 180)
			(layer "F.Fab")
			(effects
				(font
					(size 1.27 1.27)
				)
			)
		)
		(duplicate_pad_numbers_are_jumpers no)
		(fp_line
			(start 1.524 0.762)
			(end -1.524 0.762)
			(stroke
				(width 0.1524)
				(type default)
			)
			(layer "F.SilkS")
		)
		(fp_line
			(start 1.524 -0.762)
			(end 1.524 0.762)
			(stroke
				(width 0.1524)
				(type default)
			)
			(layer "F.SilkS")
		)
		(fp_line
			(start -1.524 0.762)
			(end -1.524 -0.762)
			(stroke
				(width 0.1524)
				(type default)
			)
			(layer "F.SilkS")
		)
		(fp_line
			(start -1.524 -0.762)
			(end 1.524 -0.762)
			(stroke
				(width 0.1524)
				(type default)
			)
			(layer "F.SilkS")
		)
		(fp_line
			(start 1.1049 0.724916)
			(end 1.1049 -0.724916)
			(stroke
				(width 0.1)
				(type default)
			)
			(layer "F.Fab")
		)
		(fp_line
			(start 1.1049 -0.724916)
			(end -1.1049 -0.724916)
			(stroke
				(width 0.1)
				(type default)
			)
			(layer "F.Fab")
		)
		(fp_line
			(start -1.1049 0.724916)
			(end 1.1049 0.724916)
			(stroke
				(width 0.1)
				(type default)
			)
			(layer "F.Fab")
		)
		(fp_line
			(start -1.1049 -0.724916)
			(end -1.1049 0.724916)
			(stroke
				(width 0.1)
				(type default)
			)
			(layer "F.Fab")
		)
		(pad "1" smd rect
			(at -0.889 0)
			(size 1.016 1.27)
			(layers "F.Cu" "F.Mask" "F.Paste")
			(net "P12V_SCM_R")
		)
		(pad "2" smd rect
			(at 0.889 0)
			(size 1.016 1.27)
			(layers "F.Cu" "F.Mask" "F.Paste")
			(net "GND")
		)
	)
	(footprint ""
		(layer "F.Cu")
		(at 15.436596 -388.161276 180)
		(property "Reference" "R3288"
			(at 0 0 180)
			(layer "F.SilkS")
			(hide yes)
			(effects
				(font
					(size 1.27 1.27)
				)
			)
		)
		(property "Value" ""
			(at 0 0 180)
			(layer "F.Fab")
			(effects
				(font
					(size 1.27 1.27)
				)
			)
		)
		(duplicate_pad_numbers_are_jumpers no)
		(fp_line
			(start 0.7874 0.4064)
			(end -0.7874 0.4064)
			(stroke
				(width 0.1524)
				(type default)
			)
			(layer "F.SilkS")
		)
		(fp_line
			(start 0.7874 -0.4064)
			(end 0.7874 0.4064)
			(stroke
				(width 0.1524)
				(type default)
			)
			(layer "F.SilkS")
		)
		(fp_line
			(start -0.7874 0.4064)
			(end -0.7874 -0.4064)
			(stroke
				(width 0.1524)
				(type default)
			)
			(layer "F.SilkS")
		)
		(fp_line
			(start -0.7874 -0.4064)
			(end 0.7874 -0.4064)
			(stroke
				(width 0.1524)
				(type default)
			)
			(layer "F.SilkS")
		)
		(fp_line
			(start 0.67945 0.3048)
			(end 0.120396 0.3048)
			(stroke
				(width 0.1)
				(type default)
			)
			(layer "F.Fab")
		)
		(fp_line
			(start 0.67945 -0.3048)
			(end 0.67945 0.3048)
			(stroke
				(width 0.1)
				(type default)
			)
			(layer "F.Fab")
		)
		(fp_line
			(start 0.12065 -0.2794)
			(end 0.12065 -0.3048)
			(stroke
				(width 0.1)
				(type default)
			)
			(layer "F.Fab")
		)
		(fp_line
			(start 0.12065 -0.3048)
			(end 0.67945 -0.3048)
			(stroke
				(width 0.1)
				(type default)
			)
			(layer "F.Fab")
		)
		(fp_line
			(start 0.120396 0.3048)
			(end 0.120396 0.2794)
			(stroke
				(width 0.1)
				(type default)
			)
			(layer "F.Fab")
		)
		(fp_line
			(start 0.120396 0.2794)
			(end -0.12065 0.2794)
			(stroke
				(width 0.1)
				(type default)
			)
			(layer "F.Fab")
		)
		(fp_line
			(start -0.12065 0.3048)
			(end -0.67945 0.3048)
			(stroke
				(width 0.1)
				(type default)
			)
			(layer "F.Fab")
		)
		(fp_line
			(start -0.12065 0.2794)
			(end -0.12065 0.3048)
			(stroke
				(width 0.1)
				(type default)
			)
			(layer "F.Fab")
		)
		(fp_line
			(start -0.12065 -0.2794)
			(end 0.12065 -0.2794)
			(stroke
				(width 0.1)
				(type default)
			)
			(layer "F.Fab")
		)
		(fp_line
			(start -0.12065 -0.305054)
			(end -0.12065 -0.2794)
			(stroke
				(width 0.1)
				(type default)
			)
			(layer "F.Fab")
		)
		(fp_line
			(start -0.67945 0.3048)
			(end -0.67945 -0.305054)
			(stroke
				(width 0.1)
				(type default)
			)
			(layer "F.Fab")
		)
		(fp_line
			(start -0.67945 -0.305054)
			(end -0.12065 -0.305054)
			(stroke
				(width 0.1)
				(type default)
			)
			(layer "F.Fab")
		)
		(pad "1" smd circle
			(at -0.40005 0 180)
			(size 0 0)
			(layers "F.Cu" "F.Mask" "F.Paste")
			(net "FM_P2E_SWA")
		)
		(pad "2" smd circle
			(at 0.40005 0 180)
			(size 0 0)
			(layers "F.Cu" "F.Mask" "F.Paste")
			(net "GND")
		)
	)
	(footprint ""
		(layer "F.Cu")
		(at 59.404758 -408.517344 -90)
		(property "Reference" "C703"
			(at 0 0 270)
			(layer "F.SilkS")
			(hide yes)
			(effects
				(font
					(size 1.27 1.27)
				)
			)
		)
		(property "Value" ""
			(at 0 0 270)
			(layer "F.Fab")
			(effects
				(font
					(size 1.27 1.27)
				)
			)
		)
		(duplicate_pad_numbers_are_jumpers no)
		(fp_line
			(start -0.299974 0.150114)
			(end -0.299974 -0.150114)
			(stroke
				(width 0.1)
				(type default)
			)
			(layer "F.Fab")
		)
		(fp_line
			(start 0.299974 0.150114)
			(end -0.299974 0.150114)
			(stroke
				(width 0.1)
				(type default)
			)
			(layer "F.Fab")
		)
		(fp_line
			(start -0.299974 -0.150114)
			(end 0.299974 -0.150114)
			(stroke
				(width 0.1)
				(type default)
			)
			(layer "F.Fab")
		)
		(fp_line
			(start 0.299974 -0.150114)
			(end 0.299974 0.150114)
			(stroke
				(width 0.1)
				(type default)
			)
			(layer "F.Fab")
		)
		(pad "1" smd rect
			(at -0.2667 0 270)
			(size 0.3048 0.381)
			(layers "F.Cu" "F.Mask" "F.Paste")
			(net "P5E_CPU1_PE4_TX_C_DP<3>")
		)
		(pad "2" smd rect
			(at 0.2667 0 270)
			(size 0.3048 0.381)
			(layers "F.Cu" "F.Mask" "F.Paste")
			(net "P5E_CPU1_PE4_TX_DP<3>")
		)
	)
	(footprint ""
		(layer "F.Cu")
		(at 52.17033 -17.623536 90)
		(property "Reference" "C832"
			(at 0 0 90)
			(layer "F.SilkS")
			(hide yes)
			(effects
				(font
					(size 1.27 1.27)
				)
			)
		)
		(property "Value" ""
			(at 0 0 90)
			(layer "F.Fab")
			(effects
				(font
					(size 1.27 1.27)
				)
			)
		)
		(duplicate_pad_numbers_are_jumpers no)
		(fp_line
			(start 0.299974 -0.150114)
			(end 0.299974 0.150114)
			(stroke
				(width 0.1)
				(type default)
			)
			(layer "F.Fab")
		)
		(fp_line
			(start -0.299974 -0.150114)
			(end 0.299974 -0.150114)
			(stroke
				(width 0.1)
				(type default)
			)
			(layer "F.Fab")
		)
		(fp_line
			(start 0.299974 0.150114)
			(end -0.299974 0.150114)
			(stroke
				(width 0.1)
				(type default)
			)
			(layer "F.Fab")
		)
		(fp_line
			(start -0.299974 0.150114)
			(end -0.299974 -0.150114)
			(stroke
				(width 0.1)
				(type default)
			)
			(layer "F.Fab")
		)
		(pad "1" smd rect
			(at -0.2667 0 90)
			(size 0.3048 0.381)
			(layers "F.Cu" "F.Mask" "F.Paste")
			(net "P5E_CPU1_PE1_TX_C_DN<2>")
		)
		(pad "2" smd rect
			(at 0.2667 0 90)
			(size 0.3048 0.381)
			(layers "F.Cu" "F.Mask" "F.Paste")
			(net "P5E_CPU1_PE1_TX_DN<2>")
		)
	)
)
